(kicad_pcb
	(version 20241229)
	(generator "pcbnew")
	(generator_version "9.0")
	(general
		(thickness 1.61)
		(legacy_teardrops no)
	)
	(paper "A3")
	(title_block
		(title "RDIMM DDR5 Tester")
		(date "2026-05-21")
		(rev "2.2.0")
		(company "Antmicro")
		(comment 9 "footprint 119 of 796 (U34), pads 133-199 of 676")
	)
	(layers
		(0 "F.Cu" signal)
		(4 "In1.Cu" power)
		(6 "In2.Cu" mixed)
		(8 "In3.Cu" power)
		(10 "In4.Cu" mixed)
		(12 "In5.Cu" power)
		(14 "In6.Cu" mixed)
		(16 "In7.Cu" power)
		(18 "In8.Cu" power)
		(20 "In9.Cu" mixed)
		(22 "In10.Cu" power)
		(2 "B.Cu" signal)
		(9 "F.Adhes" user "F.Adhesive")
		(11 "B.Adhes" user "B.Adhesive")
		(13 "F.Paste" user)
		(15 "B.Paste" user)
		(5 "F.SilkS" user "F.Silkscreen")
		(7 "B.SilkS" user "B.Silkscreen")
		(1 "F.Mask" user)
		(3 "B.Mask" user)
		(17 "Dwgs.User" user "User.Drawings")
		(19 "Cmts.User" user "User.Comments")
		(21 "Eco1.User" user "User.Eco1")
		(23 "Eco2.User" user "User.Eco2")
		(25 "Edge.Cuts" user)
		(27 "Margin" user)
		(31 "F.CrtYd" user "F.Courtyard")
		(29 "B.CrtYd" user "B.Courtyard")
		(35 "F.Fab" user)
		(33 "B.Fab" user)
	)
	(footprint "antmicro-footprints:BGA-676_27x27mm_Layout26x26_P1x1mm_FFVB676"
		(layer "F.Cu")
		(at 188.5 152.5 90)
		(property "Reference" "U34"
			(at -14.72 12.46 180)
			(layer "F.SilkS")
			(effects
				(font
					(size 0.7 0.7)
					(thickness 0.15)
				)
				(justify left bottom)
			)
		)
		(property "Value" "XCAU25P-2FFVB676I"
			(at 0 15.5 90)
			(layer "F.Fab")
			(effects
				(font
					(size 0.7 0.7)
					(thickness 0.15)
				)
				(justify left bottom)
			)
		)
		(property "Datasheet" "https://docs.xilinx.com/viewer/book-attachment/2PXOpPtpaABIt0fkzeBLnw/hvbsEUaOT0OxFhln7VEVyA"
			(at 0 0 90)
			(layer "F.Fab")
			(hide yes)
			(effects
				(font
					(size 1.27 1.27)
					(thickness 0.15)
				)
			)
		)
		(property "MPN" "XCAU25P-2FFVB676I"
			(at 0 0 90)
			(unlocked yes)
			(layer "F.Fab")
			(hide yes)
			(effects
				(font
					(size 1 1)
					(thickness 0.15)
				)
			)
		)
		(property "Manufacturer" "AMD-Xilinx"
			(at 0 0 90)
			(unlocked yes)
			(layer "F.Fab")
			(hide yes)
			(effects
				(font
					(size 1 1)
					(thickness 0.15)
				)
			)
		)
		(property "Author" "Antmicro"
			(at 0 0 90)
			(unlocked yes)
			(layer "F.Fab")
			(hide yes)
			(effects
				(font
					(size 1 1)
					(thickness 0.15)
				)
			)
		)
		(property "License" "Apache-2.0"
			(at 0 0 90)
			(unlocked yes)
			(layer "F.Fab")
			(hide yes)
			(effects
				(font
					(size 1 1)
					(thickness 0.15)
				)
			)
		)
		(sheetname "/FPGA Config/")
		(sheetfile "fpga-config.kicad_sch")
		(attr smd)
		(pad "AE3" smd circle
			(at -10.5 11.5 90)
			(size 0.5 0.5)
			(layers "F.Cu" "F.Mask" "F.Paste")
			(net 588 "/FPGA MGT Interface/PCIE.RXD6_N")
			(pinfunction "MGTYRXN1_224")
			(pintype "input")
			(die_length 13.961)
			(solder_mask_margin 0.075)
		)
		(pad "AE4" smd circle
			(at -9.5 11.5 90)
			(size 0.5 0.5)
			(layers "F.Cu" "F.Mask" "F.Paste")
			(net 587 "/FPGA MGT Interface/PCIE.RXD6_P")
			(pinfunction "MGTYRXP1_224")
			(pintype "input")
			(die_length 13.957)
			(solder_mask_margin 0.075)
		)
		(pad "AE5" smd circle
			(at -8.5 11.5 90)
			(size 0.5 0.5)
			(layers "F.Cu" "F.Mask" "F.Paste")
			(net 1 "GND")
			(pinfunction "GND")
			(pintype "passive")
			(solder_mask_margin 0.075)
		)
		(pad "AE6" smd circle
			(at -7.5 11.5 90)
			(size 0.5 0.5)
			(layers "F.Cu" "F.Mask" "F.Paste")
			(net 1 "GND")
			(pinfunction "GND")
			(pintype "passive")
			(solder_mask_margin 0.075)
		)
		(pad "AE7" smd circle
			(at -6.5 11.5 90)
			(size 0.5 0.5)
			(layers "F.Cu" "F.Mask" "F.Paste")
			(net 172 "+1V2_MGTAVTT")
			(pinfunction "MGTAVTT_R")
			(pintype "passive")
			(solder_mask_margin 0.075)
		)
		(pad "AE8" smd circle
			(at -5.5 11.5 90)
			(size 0.5 0.5)
			(layers "F.Cu" "F.Mask" "F.Paste")
			(net 562 "/FPGA MGT Interface/GTY_224_TX1_N")
			(pinfunction "MGTYTXN1_224")
			(pintype "output")
			(die_length 13.144)
			(solder_mask_margin 0.075)
		)
		(pad "AE9" smd circle
			(at -4.5 11.5 90)
			(size 0.5 0.5)
			(layers "F.Cu" "F.Mask" "F.Paste")
			(net 559 "/FPGA MGT Interface/GTY_224_TX1_P")
			(pinfunction "MGTYTXP1_224")
			(pintype "output")
			(die_length 13.169)
			(solder_mask_margin 0.075)
		)
		(pad "AE10" smd circle
			(at -3.5 11.5 90)
			(size 0.5 0.5)
			(layers "F.Cu" "F.Mask" "F.Paste")
			(net 1 "GND")
			(pinfunction "GND")
			(pintype "passive")
			(solder_mask_margin 0.075)
		)
		(pad "AE11" smd circle
			(at -2.5 11.5 90)
			(size 0.5 0.5)
			(layers "F.Cu" "F.Mask" "F.Paste")
			(net 354 "/FPGA Config/FLASH.IO3")
			(pinfunction "D03_0")
			(pintype "bidirectional")
			(die_length 17.943)
			(solder_mask_margin 0.075)
		)
		(pad "AE12" smd circle
			(at -1.5 11.5 90)
			(size 0.5 0.5)
			(layers "F.Cu" "F.Mask" "F.Paste")
			(net 239 "/Debug FTDI + VNA/JTAG.TCK")
			(pinfunction "TCK_0")
			(pintype "input")
			(die_length 17.51)
			(solder_mask_margin 0.075)
		)
		(pad "AE13" smd circle
			(at -0.5 11.5 90)
			(size 0.5 0.5)
			(layers "F.Cu" "F.Mask" "F.Paste")
			(net 180 "HOT_SWAP_GREEN")
			(pinfunction "IO_L2P_AD10P_84")
			(pintype "bidirectional")
			(die_length 16.056)
			(solder_mask_margin 0.075)
		)
		(pad "AE14" smd circle
			(at 0.5 11.5 90)
			(size 0.5 0.5)
			(layers "F.Cu" "F.Mask" "F.Paste")
			(net 1 "GND")
			(pinfunction "GND")
			(pintype "passive")
			(solder_mask_margin 0.075)
		)
		(pad "AE15" smd circle
			(at 1.5 11.5 90)
			(size 0.5 0.5)
			(layers "F.Cu" "F.Mask" "F.Paste")
			(net 626 "USER_IN")
			(pinfunction "IO_L3N_AD9N_84")
			(pintype "bidirectional")
			(die_length 12.961)
			(solder_mask_margin 0.075)
		)
		(pad "AE16" smd circle
			(at 2.5 11.5 90)
			(size 0.5 0.5)
			(layers "F.Cu" "F.Mask" "F.Paste")
			(net 57 "/DDR5 RDIMM/A.DQ12")
			(pinfunction "IO_L18N_T2U_N11_AD2N_64")
			(pintype "bidirectional")
			(die_length 17.823)
			(solder_mask_margin 0.075)
		)
		(pad "AE17" smd circle
			(at 3.5 11.5 90)
			(size 0.5 0.5)
			(layers "F.Cu" "F.Mask" "F.Paste")
			(net 144 "/DDR5 RDIMM/A.DQ15")
			(pinfunction "IO_L17P_T2U_N8_AD10P_64")
			(pintype "bidirectional")
			(die_length 16.857)
			(solder_mask_margin 0.075)
		)
		(pad "AE18" smd circle
			(at 4.5 11.5 90)
			(size 0.5 0.5)
			(layers "F.Cu" "F.Mask" "F.Paste")
			(net 487 "unconnected-(U34B-IO_T2U_N12_64-PadAE18)")
			(pinfunction "IO_T2U_N12_64")
			(pintype "bidirectional+no_connect")
			(die_length 15.893)
			(solder_mask_margin 0.075)
		)
		(pad "AE19" smd circle
			(at 5.5 11.5 90)
			(size 0.5 0.5)
			(layers "F.Cu" "F.Mask" "F.Paste")
			(net 1 "GND")
			(pinfunction "GND")
			(pintype "passive")
			(solder_mask_margin 0.075)
		)
		(pad "AE20" smd circle
			(at 6.5 11.5 90)
			(size 0.5 0.5)
			(layers "F.Cu" "F.Mask" "F.Paste")
			(net 104 "/DDR5 RDIMM/A.DQS1_N")
			(pinfunction "IO_L13N_T2L_N1_GC_QBC_64")
			(pintype "bidirectional")
			(die_length 15.203)
			(solder_mask_margin 0.075)
		)
		(pad "AE21" smd circle
			(at 7.5 11.5 90)
			(size 0.5 0.5)
			(layers "F.Cu" "F.Mask" "F.Paste")
			(net 62 "/DDR5 RDIMM/A.DQ21")
			(pinfunction "IO_L11N_T1U_N9_GC_64")
			(pintype "bidirectional")
			(die_length 14.796)
			(solder_mask_margin 0.075)
		)
		(pad "AE22" smd circle
			(at 8.5 11.5 90)
			(size 0.5 0.5)
			(layers "F.Cu" "F.Mask" "F.Paste")
			(net 108 "/DDR5 RDIMM/A.DQS2_P")
			(pinfunction "IO_L7P_T1L_N0_QBC_AD13P_64")
			(pintype "bidirectional")
			(die_length 17.07)
			(solder_mask_margin 0.075)
		)
		(pad "AE23" smd circle
			(at 9.5 11.5 90)
			(size 0.5 0.5)
			(layers "F.Cu" "F.Mask" "F.Paste")
			(net 60 "/DDR5 RDIMM/A.DQ17")
			(pinfunction "IO_L8N_T1L_N3_AD5N_64")
			(pintype "bidirectional")
			(die_length 14.312)
			(solder_mask_margin 0.075)
		)
		(pad "AE24" smd circle
			(at 10.5 11.5 90)
			(size 0.5 0.5)
			(layers "F.Cu" "F.Mask" "F.Paste")
			(net 1 "GND")
			(pinfunction "GND")
			(pintype "passive")
			(solder_mask_margin 0.075)
		)
		(pad "AE25" smd circle
			(at 11.5 11.5 90)
			(size 0.5 0.5)
			(layers "F.Cu" "F.Mask" "F.Paste")
			(net 114 "/DDR5 RDIMM/A.DQS3_P")
			(pinfunction "IO_L1P_T0L_N0_DBC_64")
			(pintype "bidirectional")
			(die_length 15.008)
			(solder_mask_margin 0.075)
		)
		(pad "AE26" smd circle
			(at 12.5 11.5 90)
			(size 0.5 0.5)
			(layers "F.Cu" "F.Mask" "F.Paste")
			(net 115 "/DDR5 RDIMM/A.DQS3_N")
			(pinfunction "IO_L1N_T0L_N1_DBC_64")
			(pintype "bidirectional")
			(die_length 15.074)
			(solder_mask_margin 0.075)
		)
		(pad "AF1" smd circle
			(at -12.5 12.5 90)
			(size 0.5 0.5)
			(layers "F.Cu" "F.Mask" "F.Paste")
			(net 590 "/FPGA MGT Interface/PCIE.RXD7_N")
			(pinfunction "MGTYRXN0_224")
			(pintype "input")
			(die_length 16.143)
			(solder_mask_margin 0.075)
		)
		(pad "AF2" smd circle
			(at -11.5 12.5 90)
			(size 0.5 0.5)
			(layers "F.Cu" "F.Mask" "F.Paste")
			(net 589 "/FPGA MGT Interface/PCIE.RXD7_P")
			(pinfunction "MGTYRXP0_224")
			(pintype "input")
			(die_length 16.128)
			(solder_mask_margin 0.075)
		)
		(pad "AF3" smd circle
			(at -10.5 12.5 90)
			(size 0.5 0.5)
			(layers "F.Cu" "F.Mask" "F.Paste")
			(net 1 "GND")
			(pinfunction "GND")
			(pintype "passive")
			(solder_mask_margin 0.075)
		)
		(pad "AF4" smd circle
			(at -9.5 12.5 90)
			(size 0.5 0.5)
			(layers "F.Cu" "F.Mask" "F.Paste")
			(net 1 "GND")
			(pinfunction "GND")
			(pintype "passive")
			(solder_mask_margin 0.075)
		)
		(pad "AF5" smd circle
			(at -8.5 12.5 90)
			(size 0.5 0.5)
			(layers "F.Cu" "F.Mask" "F.Paste")
			(net 1 "GND")
			(pinfunction "GND")
			(pintype "passive")
			(solder_mask_margin 0.075)
		)
		(pad "AF6" smd circle
			(at -7.5 12.5 90)
			(size 0.5 0.5)
			(layers "F.Cu" "F.Mask" "F.Paste")
			(net 558 "/FPGA MGT Interface/GTY_224_TX0_N")
			(pinfunction "MGTYTXN0_224")
			(pintype "output")
			(die_length 16.305)
			(solder_mask_margin 0.075)
		)
		(pad "AF7" smd circle
			(at -6.5 12.5 90)
			(size 0.5 0.5)
			(layers "F.Cu" "F.Mask" "F.Paste")
			(net 557 "/FPGA MGT Interface/GTY_224_TX0_P")
			(pinfunction "MGTYTXP0_224")
			(pintype "output")
			(die_length 16.298)
			(solder_mask_margin 0.075)
		)
		(pad "AF8" smd circle
			(at -5.5 12.5 90)
			(size 0.5 0.5)
			(layers "F.Cu" "F.Mask" "F.Paste")
			(net 1 "GND")
			(pinfunction "GND")
			(pintype "passive")
			(solder_mask_margin 0.075)
		)
		(pad "AF9" smd circle
			(at -4.5 12.5 90)
			(size 0.5 0.5)
			(layers "F.Cu" "F.Mask" "F.Paste")
			(net 1 "GND")
			(pinfunction "GND")
			(pintype "passive")
			(solder_mask_margin 0.075)
		)
		(pad "AF10" smd circle
			(at -3.5 12.5 90)
			(size 0.5 0.5)
			(layers "F.Cu" "F.Mask" "F.Paste")
			(net 1 "GND")
			(pinfunction "GND")
			(pintype "passive")
			(solder_mask_margin 0.075)
		)
		(pad "AF11" smd circle
			(at -2.5 12.5 90)
			(size 0.5 0.5)
			(layers "F.Cu" "F.Mask" "F.Paste")
			(net 1 "GND")
			(pinfunction "GND")
			(pintype "passive")
			(solder_mask_margin 0.075)
		)
		(pad "AF12" smd circle
			(at -1.5 12.5 90)
			(size 0.5 0.5)
			(layers "F.Cu" "F.Mask" "F.Paste")
			(net 773 "MODE2")
			(pinfunction "M2_0")
			(pintype "input")
			(die_length 20.09)
			(solder_mask_margin 0.075)
		)
		(pad "AF13" smd circle
			(at -0.5 12.5 90)
			(size 0.5 0.5)
			(layers "F.Cu" "F.Mask" "F.Paste")
			(net 69 "HOT_SWAP_BUTTON")
			(pinfunction "IO_L2N_AD10N_84")
			(pintype "bidirectional")
			(die_length 16.382)
			(solder_mask_margin 0.075)
		)
		(pad "AF14" smd circle
			(at 0.5 12.5 90)
			(size 0.5 0.5)
			(layers "F.Cu" "F.Mask" "F.Paste")
			(net 179 "HOT_SWAP_YELLOW")
			(pinfunction "IO_L1P_AD11P_84")
			(pintype "bidirectional")
			(die_length 14.637)
			(solder_mask_margin 0.075)
		)
		(pad "AF15" smd circle
			(at 1.5 12.5 90)
			(size 0.5 0.5)
			(layers "F.Cu" "F.Mask" "F.Paste")
			(net 702 "HOT_SWAP_RED")
			(pinfunction "IO_L1N_AD11N_84")
			(pintype "bidirectional")
			(die_length 14.515)
			(solder_mask_margin 0.075)
		)
		(pad "AF16" smd circle
			(at 2.5 12.5 90)
			(size 0.5 0.5)
			(layers "F.Cu" "F.Mask" "F.Paste")
			(net 1 "GND")
			(pinfunction "GND")
			(pintype "passive")
			(solder_mask_margin 0.075)
		)
		(pad "AF17" smd circle
			(at 3.5 12.5 90)
			(size 0.5 0.5)
			(layers "F.Cu" "F.Mask" "F.Paste")
			(net 143 "/DDR5 RDIMM/A.DQ14")
			(pinfunction "IO_L17N_T2U_N9_AD10N_64")
			(pintype "bidirectional")
			(die_length 17.295)
			(solder_mask_margin 0.075)
		)
		(pad "AF18" smd circle
			(at 4.5 12.5 90)
			(size 0.5 0.5)
			(layers "F.Cu" "F.Mask" "F.Paste")
			(net 55 "/DDR5 RDIMM/A.DQ8")
			(pinfunction "IO_L15P_T2L_N4_AD11P_64")
			(pintype "bidirectional")
			(die_length 16.158)
			(solder_mask_margin 0.075)
		)
		(pad "AF19" smd circle
			(at 5.5 12.5 90)
			(size 0.5 0.5)
			(layers "F.Cu" "F.Mask" "F.Paste")
			(net 56 "/DDR5 RDIMM/A.DQ9")
			(pinfunction "IO_L15N_T2L_N5_AD11N_64")
			(pintype "bidirectional")
			(die_length 16.079)
			(solder_mask_margin 0.075)
		)
		(pad "AF20" smd circle
			(at 6.5 12.5 90)
			(size 0.5 0.5)
			(layers "F.Cu" "F.Mask" "F.Paste")
			(net 491 "unconnected-(U34B-IO_T1U_N12_64-PadAF20)")
			(pinfunction "IO_T1U_N12_64")
			(pintype "bidirectional+no_connect")
			(die_length 14.747)
			(solder_mask_margin 0.075)
		)
		(pad "AF21" smd circle
			(at 7.5 12.5 90)
			(size 0.5 0.5)
			(layers "F.Cu" "F.Mask" "F.Paste")
			(net 1 "GND")
			(pinfunction "GND")
			(pintype "passive")
			(solder_mask_margin 0.075)
		)
		(pad "AF22" smd circle
			(at 8.5 12.5 90)
			(size 0.5 0.5)
			(layers "F.Cu" "F.Mask" "F.Paste")
			(net 109 "/DDR5 RDIMM/A.DQS2_N")
			(pinfunction "IO_L7N_T1L_N1_QBC_AD13N_64")
			(pintype "bidirectional")
			(die_length 17.004)
			(solder_mask_margin 0.075)
		)
		(pad "AF23" smd circle
			(at 9.5 12.5 90)
			(size 0.5 0.5)
			(layers "F.Cu" "F.Mask" "F.Paste")
			(net 547 "/FPGA banks HP/VRP_64")
			(pinfunction "IO_T0U_N12_VRP_64")
			(pintype "bidirectional")
			(die_length 16.259)
			(solder_mask_margin 0.075)
		)
		(pad "AF24" smd circle
			(at 10.5 12.5 90)
			(size 0.5 0.5)
			(layers "F.Cu" "F.Mask" "F.Paste")
			(net 64 "/DDR5 RDIMM/A.DQ25")
			(pinfunction "IO_L3P_T0L_N4_AD15P_64")
			(pintype "bidirectional")
			(die_length 16.413)
			(solder_mask_margin 0.075)
		)
		(pad "AF25" smd circle
			(at 11.5 12.5 90)
			(size 0.5 0.5)
			(layers "F.Cu" "F.Mask" "F.Paste")
			(net 155 "/DDR5 RDIMM/A.DQ27")
			(pinfunction "IO_L3N_T0L_N5_AD15N_64")
			(pintype "bidirectional")
			(die_length 16.361)
			(solder_mask_margin 0.075)
		)
		(pad "AF26" smd circle
			(at 12.5 12.5 90)
			(size 0.5 0.5)
			(layers "F.Cu" "F.Mask" "F.Paste")
			(net 1 "GND")
			(pinfunction "GND")
			(pintype "passive")
			(solder_mask_margin 0.075)
		)
		(pad "B1" smd circle
			(at -12.5 -11.5 90)
			(size 0.5 0.5)
			(layers "F.Cu" "F.Mask" "F.Paste")
			(net 492 "unconnected-(U34L-NC-PadB1)")
			(pinfunction "NC")
			(pintype "no_connect")
			(solder_mask_margin 0.075)
		)
		(pad "B2" smd circle
			(at -11.5 -11.5 90)
			(size 0.5 0.5)
			(layers "F.Cu" "F.Mask" "F.Paste")
			(net 493 "unconnected-(U34L-NC-PadB2)")
			(pinfunction "NC")
			(pintype "no_connect")
			(solder_mask_margin 0.075)
		)
		(pad "B3" smd circle
			(at -10.5 -11.5 90)
			(size 0.5 0.5)
			(layers "F.Cu" "F.Mask" "F.Paste")
			(net 1 "GND")
			(pinfunction "GND")
			(pintype "passive")
			(solder_mask_margin 0.075)
		)
		(pad "B4" smd circle
			(at -9.5 -11.5 90)
			(size 0.5 0.5)
			(layers "F.Cu" "F.Mask" "F.Paste")
			(net 1 "GND")
			(pinfunction "GND")
			(pintype "passive")
			(solder_mask_margin 0.075)
		)
		(pad "B5" smd circle
			(at -8.5 -11.5 90)
			(size 0.5 0.5)
			(layers "F.Cu" "F.Mask" "F.Paste")
			(net 1 "GND")
			(pinfunction "GND")
			(pintype "passive")
			(solder_mask_margin 0.075)
		)
		(pad "B6" smd circle
			(at -7.5 -11.5 90)
			(size 0.5 0.5)
			(layers "F.Cu" "F.Mask" "F.Paste")
			(net 494 "unconnected-(U34L-NC-PadB6)")
			(pinfunction "NC")
			(pintype "no_connect")
			(solder_mask_margin 0.075)
		)
		(pad "B7" smd circle
			(at -6.5 -11.5 90)
			(size 0.5 0.5)
			(layers "F.Cu" "F.Mask" "F.Paste")
			(net 495 "unconnected-(U34L-NC-PadB7)")
			(pinfunction "NC")
			(pintype "no_connect")
			(solder_mask_margin 0.075)
		)
		(pad "B8" smd circle
			(at -5.5 -11.5 90)
			(size 0.5 0.5)
			(layers "F.Cu" "F.Mask" "F.Paste")
			(net 1 "GND")
			(pinfunction "GND")
			(pintype "passive")
			(solder_mask_margin 0.075)
		)
		(pad "B9" smd circle
			(at -4.5 -11.5 90)
			(size 0.5 0.5)
			(layers "F.Cu" "F.Mask" "F.Paste")
			(net 391 "/Debug FTDI + VNA/AUX.TDI")
			(pinfunction "IO_L10P_AD2P_86")
			(pintype "bidirectional")
			(die_length 18.904)
			(solder_mask_margin 0.075)
		)
		(pad "B10" smd circle
			(at -3.5 -11.5 90)
			(size 0.5 0.5)
			(layers "F.Cu" "F.Mask" "F.Paste")
			(net 497 "unconnected-(U34G-IO_L11P_AD1P_86-PadB10)")
			(pinfunction "IO_L11P_AD1P_86")
			(pintype "bidirectional+no_connect")
			(die_length 18.046)
			(solder_mask_margin 0.075)
		)
		(pad "B11" smd circle
			(at -2.5 -11.5 90)
			(size 0.5 0.5)
			(layers "F.Cu" "F.Mask" "F.Paste")
			(net 498 "unconnected-(U34G-IO_L12N_AD0N_86-PadB11)")
			(pinfunction "IO_L12N_AD0N_86")
			(pintype "bidirectional+no_connect")
			(die_length 16.738)
			(solder_mask_margin 0.075)
		)
		(pad "B12" smd circle
			(at -1.5 -11.5 90)
			(size 0.5 0.5)
			(layers "F.Cu" "F.Mask" "F.Paste")
			(net 500 "HDMI_IN_HPD")
			(pinfunction "IO_L10N_AD10N_87")
			(pintype "bidirectional")
			(die_length 14.992)
			(solder_mask_margin 0.075)
		)
		(pad "B13" smd circle
			(at -0.5 -11.5 90)
			(size 0.5 0.5)
			(layers "F.Cu" "F.Mask" "F.Paste")
			(net 1 "GND")
			(pinfunction "GND")
			(pintype "passive")
			(solder_mask_margin 0.075)
		)
		(pad "B14" smd circle
			(at 0.5 -11.5 90)
			(size 0.5 0.5)
			(layers "F.Cu" "F.Mask" "F.Paste")
			(net 772 "SD_SEL")
			(pinfunction "IO_L12P_AD8P_87")
			(pintype "bidirectional")
			(die_length 13.138)
			(solder_mask_margin 0.075)
		)
		(pad "B15" smd circle
			(at 1.5 -11.5 90)
			(size 0.5 0.5)
			(layers "F.Cu" "F.Mask" "F.Paste")
			(net 436 "/Ethernet/ETH.TXD0")
			(pinfunction "IO_L17P_T2U_N8_AD10P_67")
			(pintype "bidirectional")
			(die_length 17.648)
			(solder_mask_margin 0.075)
		)
		(pad "B16" smd circle
			(at 2.5 -11.5 90)
			(size 0.5 0.5)
			(layers "F.Cu" "F.Mask" "F.Paste")
			(net 666 "unconnected-(U34E-IO_T2U_N12_67-PadB16)")
			(pinfunction "IO_T2U_N12_67")
			(pintype "bidirectional+no_connect")
			(die_length 16.783)
			(solder_mask_margin 0.075)
		)
		(pad "B17" smd circle
			(at 3.5 -11.5 90)
			(size 0.5 0.5)
			(layers "F.Cu" "F.Mask" "F.Paste")
			(net 394 "/Ethernet/ETH.RXD1")
			(pinfunction "IO_L15N_T2L_N5_AD11N_67")
			(pintype "bidirectional")
			(die_length 15.811)
			(solder_mask_margin 0.075)
		)
	)
)
